(kicad_pcb
	(version 20241229)
	(generator "pcbnew")
	(generator_version "9.0")
	(general
		(thickness 1.6296)
		(legacy_teardrops no)
	)
	(paper "A3")
	(title_block
		(title "Thunderbolt to 10GbE adapter")
		(date "2026-04-21")
		(rev "1.1.0")
		(company "Antmicro Ltd")
		(comment 1 "www.antmicro.com")
		(comment 9 "footprints 46-49 of 703")
	)
	(layers
		(0 "F.Cu" signal)
		(4 "In1.Cu" signal)
		(6 "In2.Cu" signal)
		(8 "In3.Cu" signal)
		(10 "In4.Cu" signal)
		(12 "In5.Cu" signal)
		(14 "In6.Cu" signal)
		(2 "B.Cu" signal)
		(9 "F.Adhes" user "F.Adhesive")
		(11 "B.Adhes" user "B.Adhesive")
		(13 "F.Paste" user)
		(15 "B.Paste" user)
		(5 "F.SilkS" user "F.Silkscreen")
		(7 "B.SilkS" user "B.Silkscreen")
		(1 "F.Mask" user)
		(3 "B.Mask" user)
		(17 "Dwgs.User" user "User.Drawings")
		(19 "Cmts.User" user "User.Comments")
		(21 "Eco1.User" user "User.Eco1")
		(23 "Eco2.User" user "User.Eco2")
		(25 "Edge.Cuts" user)
		(27 "Margin" user)
		(31 "F.CrtYd" user "F.Courtyard")
		(29 "B.CrtYd" user "B.Courtyard")
		(35 "F.Fab" user)
		(33 "B.Fab" user)
	)
	(footprint "antmicro-footprints:LED_0603_1608Metric_G"
		(layer "F.Cu")
		(at 130.4 143.6 -90)
		(descr "LED SMD 0603 Green")
		(tags "LED SMD 0603 Green")
		(property "Reference" "D18"
			(at 1 0.8 270)
			(layer "F.SilkS")
			(effects
				(font
					(size 0.7 0.7)
					(thickness 0.15)
				)
				(justify left bottom)
			)
		)
		(property "Value" "LED_G_0603_LTST-C190GKT"
			(at -0.001 1.599 270)
			(layer "F.Fab")
			(effects
				(font
					(size 0.7 0.7)
					(thickness 0.15)
				)
				(justify left bottom)
			)
		)
		(property "Datasheet" "https://media.digikey.com/pdf/Data%20Sheets/Lite-On%20PDFs/LTST-C190GKT.pdf"
			(at 0 0 270)
			(layer "F.Fab")
			(hide yes)
			(effects
				(font
					(size 1.27 1.27)
					(thickness 0.15)
				)
			)
		)
		(property "Description" "LED, Green, SMD, 0603, 20 mA, 2.1 V, 569 nm"
			(at 0 0 270)
			(layer "F.Fab")
			(hide yes)
			(effects
				(font
					(size 1.27 1.27)
					(thickness 0.15)
				)
			)
		)
		(property "MPN" "LTST-C190GKT"
			(at 0 0 270)
			(unlocked yes)
			(layer "F.Fab")
			(hide yes)
			(effects
				(font
					(size 1 1)
					(thickness 0.15)
				)
			)
		)
		(property "Manufacturer" "Lite-On"
			(at 0 0 270)
			(unlocked yes)
			(layer "F.Fab")
			(hide yes)
			(effects
				(font
					(size 1 1)
					(thickness 0.15)
				)
			)
		)
		(property "Author" "Antmicro"
			(at 0 0 270)
			(unlocked yes)
			(layer "F.Fab")
			(hide yes)
			(effects
				(font
					(size 1 1)
					(thickness 0.15)
				)
			)
		)
		(property "License" "Apache-2.0"
			(at 0 0 270)
			(unlocked yes)
			(layer "F.Fab")
			(hide yes)
			(effects
				(font
					(size 1 1)
					(thickness 0.15)
				)
			)
		)
		(property "Color" "Green"
			(at 0 0 270)
			(unlocked yes)
			(layer "F.Fab")
			(hide yes)
			(effects
				(font
					(size 1 1)
					(thickness 0.15)
				)
			)
		)
		(sheetname "/Power input/")
		(sheetfile "power_input.kicad_sch")
		(attr smd)
		(fp_line
			(start 0.22 0.35)
			(end -0.22 0.35)
			(stroke
				(width 0.15)
				(type solid)
			)
			(layer "F.SilkS")
		)
		(fp_line
			(start -0.094672 0.201008)
			(end -0.094672 -0.198992)
			(stroke
				(width 0.1)
				(type solid)
			)
			(layer "F.SilkS")
		)
		(fp_line
			(start 0.105328 0.201008)
			(end -0.094672 0.001008)
			(stroke
				(width 0.1)
				(type solid)
			)
			(layer "F.SilkS")
		)
		(fp_line
			(start 0.105328 0.201008)
			(end 0.105328 -0.198992)
			(stroke
				(width 0.1)
				(type solid)
			)
			(layer "F.SilkS")
		)
		(fp_line
			(start -0.094672 0.001008)
			(end -0.24 0.001008)
			(stroke
				(width 0.1)
				(type solid)
			)
			(layer "F.SilkS")
		)
		(fp_line
			(start -0.094672 0.001008)
			(end 0.105328 -0.198992)
			(stroke
				(width 0.1)
				(type solid)
			)
			(layer "F.SilkS")
		)
		(fp_line
			(start 0.105328 0.001008)
			(end 0.24 0.001)
			(stroke
				(width 0.1)
				(type solid)
			)
			(layer "F.SilkS")
		)
		(fp_line
			(start -1.18 -0.319)
			(end -1.18 0.321)
			(stroke
				(width 0.15)
				(type solid)
			)
			(layer "F.SilkS")
		)
		(fp_line
			(start 0.22 -0.35)
			(end -0.22 -0.35)
			(stroke
				(width 0.15)
				(type solid)
			)
			(layer "F.SilkS")
		)
		(fp_rect
			(start 1.25 0.65)
			(end -1.25 -0.65)
			(stroke
				(width 0.05)
				(type solid)
			)
			(fill no)
			(layer "F.CrtYd")
		)
		(fp_line
			(start -0.199 0.2)
			(end -0.199 0.1)
			(stroke
				(width 0.15)
				(type solid)
			)
			(layer "F.Fab")
		)
		(fp_line
			(start 0.201 0.2)
			(end 0.201 0)
			(stroke
				(width 0.15)
				(type solid)
			)
			(layer "F.Fab")
		)
		(fp_line
			(start -0.199 0)
			(end -0.597 0)
			(stroke
				(width 0.15)
				(type solid)
			)
			(layer "F.Fab")
		)
		(fp_line
			(start -0.101 0)
			(end 0.201 0.2)
			(stroke
				(width 0.15)
				(type solid)
			)
			(layer "F.Fab")
		)
		(fp_line
			(start 0.201 0)
			(end 0.201 -0.202)
			(stroke
				(width 0.15)
				(type solid)
			)
			(layer "F.Fab")
		)
		(fp_line
			(start 0.599 0)
			(end 0.201 0)
			(stroke
				(width 0.15)
				(type solid)
			)
			(layer "F.Fab")
		)
		(fp_line
			(start -0.199 -0.202)
			(end -0.199 0.1)
			(stroke
				(width 0.15)
				(type solid)
			)
			(layer "F.Fab")
		)
		(fp_line
			(start 0.201 -0.202)
			(end -0.101 0)
			(stroke
				(width 0.15)
				(type solid)
			)
			(layer "F.Fab")
		)
		(fp_rect
			(start 0.848 0.4)
			(end -0.85 -0.402)
			(stroke
				(width 0.15)
				(type solid)
			)
			(fill no)
			(layer "F.Fab")
		)
		(fp_text user "Author: Antmicro"
			(at -1.4224 4.799 270)
			(layer "F.Fab")
			(effects
				(font
					(size 0.7 0.7)
					(thickness 0.15)
				)
				(justify left bottom)
			)
		)
		(fp_text user "License: Apache-2.0"
			(at -1.4224 3.599 270)
			(layer "F.Fab")
			(effects
				(font
					(size 0.7 0.7)
					(thickness 0.15)
				)
				(justify left bottom)
			)
		)
		(fp_text user "${REFERENCE}"
			(at -1.4224 5.999 270)
			(layer "F.Fab")
			(effects
				(font
					(size 0.7 0.7)
					(thickness 0.15)
				)
				(justify left bottom)
			)
		)
		(pad "1" smd roundrect
			(at -0.7 0 90)
			(size 0.8 1)
			(layers "F.Cu" "F.Mask" "F.Paste")
			(roundrect_rratio 0.2)
			(net 23 "GND")
			(pinfunction "C")
			(pintype "passive")
		)
		(pad "2" smd roundrect
			(at 0.7 0 90)
			(size 0.8 1)
			(layers "F.Cu" "F.Mask" "F.Paste")
			(roundrect_rratio 0.2)
			(net 421 "Net-(D18-A)")
			(pinfunction "A")
			(pintype "passive")
		)
	)
	(footprint "antmicro-footprints:C_0402_1005Metric"
		(layer "F.Cu")
		(at 151.955 98.574999)
		(descr "Capacitor SMD 0402")
		(tags "capacitor SMD 0402")
		(property "Reference" "C158"
			(at 23.294999 19.625001 0)
			(layer "F.SilkS")
			(effects
				(font
					(size 0.7 0.7)
					(thickness 0.15)
				)
			)
		)
		(property "Value" "C_100n_0402"
			(at -1.022927 2.155213 0)
			(layer "F.Fab")
			(effects
				(font
					(size 0.7 0.7)
					(thickness 0.15)
				)
				(justify left bottom)
			)
		)
		(property "Datasheet" "https://www.murata.com/products/productdetail?partno=GRM155R61H104KE14%23"
			(at 0 0 0)
			(layer "F.Fab")
			(hide yes)
			(effects
				(font
					(size 1.27 1.27)
					(thickness 0.15)
				)
			)
		)
		(property "Description" "SMD Multilayer Ceramic Capacitor, 0.1 µF, 50 V, 0402 [1005 Metric], ± 10%, X5R, GRM Series"
			(at 0 0 0)
			(layer "F.Fab")
			(hide yes)
			(effects
				(font
					(size 1.27 1.27)
					(thickness 0.15)
				)
			)
		)
		(property "MPN" "GRM155R61H104KE14D"
			(at 0 0 0)
			(unlocked yes)
			(layer "F.Fab")
			(hide yes)
			(effects
				(font
					(size 1 1)
					(thickness 0.15)
				)
			)
		)
		(property "Val" "100n"
			(at 0 0 0)
			(unlocked yes)
			(layer "F.Fab")
			(hide yes)
			(effects
				(font
					(size 1 1)
					(thickness 0.15)
				)
			)
		)
		(property "Voltage" "50V"
			(at 0 0 0)
			(unlocked yes)
			(layer "F.Fab")
			(hide yes)
			(effects
				(font
					(size 1 1)
					(thickness 0.15)
				)
			)
		)
		(property "Dielectric" "X5R"
			(at 0 0 0)
			(unlocked yes)
			(layer "F.Fab")
			(hide yes)
			(effects
				(font
					(size 1 1)
					(thickness 0.15)
				)
			)
		)
		(property "Manufacturer" "Murata"
			(at 0 0 0)
			(unlocked yes)
			(layer "F.Fab")
			(hide yes)
			(effects
				(font
					(size 1 1)
					(thickness 0.15)
				)
			)
		)
		(property "License" "Apache-2.0"
			(at 0 0 0)
			(unlocked yes)
			(layer "F.Fab")
			(hide yes)
			(effects
				(font
					(size 1 1)
					(thickness 0.15)
				)
			)
		)
		(property "Author" "Antmicro"
			(at 0 0 0)
			(unlocked yes)
			(layer "F.Fab")
			(hide yes)
			(effects
				(font
					(size 1 1)
					(thickness 0.15)
				)
			)
		)
		(sheetname "/X710-AT2 power/")
		(sheetfile "x710-at2-power.kicad_sch")
		(attr smd)
		(fp_rect
			(start -0.925 -0.47)
			(end 0.925 0.47)
			(stroke
				(width 0.05)
				(type default)
			)
			(fill no)
			(layer "F.CrtYd")
		)
		(fp_line
			(start -0.494 -0.25)
			(end 0.504 -0.25)
			(stroke
				(width 0.15)
				(type solid)
			)
			(layer "F.Fab")
		)
		(fp_line
			(start -0.494 0.248)
			(end -0.494 -0.25)
			(stroke
				(width 0.15)
				(type solid)
			)
			(layer "F.Fab")
		)
		(fp_line
			(start 0.504 -0.25)
			(end 0.504 0.248)
			(stroke
				(width 0.15)
				(type solid)
			)
			(layer "F.Fab")
		)
		(fp_line
			(start 0.504 0.248)
			(end -0.494 0.248)
			(stroke
				(width 0.15)
				(type solid)
			)
			(layer "F.Fab")
		)
		(fp_text user "License: Apache-2.0"
			(at -0.939 5.799 0)
			(layer "F.Fab")
			(effects
				(font
					(size 0.7 0.7)
					(thickness 0.15)
				)
				(justify left bottom)
			)
		)
		(fp_text user "${REFERENCE}"
			(at -0.939 4.599 0)
			(layer "F.Fab")
			(effects
				(font
					(size 0.7 0.7)
					(thickness 0.15)
				)
				(justify left bottom)
			)
		)
		(fp_text user "Author: Antmicro"
			(at -0.939 3.399 0)
			(layer "F.Fab")
			(effects
				(font
					(size 0.7 0.7)
					(thickness 0.15)
				)
				(justify left bottom)
			)
		)
		(pad "1" smd roundrect
			(at -0.48 0)
			(size 0.59 0.64)
			(layers "F.Cu" "F.Mask" "F.Paste")
			(roundrect_rratio 0.25)
			(net 23 "GND")
			(pintype "passive")
		)
		(pad "2" smd roundrect
			(at 0.48 0)
			(size 0.59 0.64)
			(layers "F.Cu" "F.Mask" "F.Paste")
			(roundrect_rratio 0.25)
			(net 136 "+1V0")
			(pintype "passive")
		)
	)
	(footprint "antmicro-footprints:C_0402_1005Metric"
		(layer "F.Cu")
		(at 154.900001 111.85)
		(descr "Capacitor SMD 0402")
		(tags "capacitor SMD 0402")
		(property "Reference" "C116"
			(at 13.650003 16.799998 0)
			(layer "F.SilkS")
			(effects
				(font
					(size 0.7 0.7)
					(thickness 0.15)
				)
			)
		)
		(property "Value" "C_100n_0402"
			(at -1.022927 2.155213 0)
			(layer "F.Fab")
			(effects
				(font
					(size 0.7 0.7)
					(thickness 0.15)
				)
				(justify left bottom)
			)
		)
		(property "Datasheet" "https://www.murata.com/products/productdetail?partno=GRM155R61H104KE14%23"
			(at 0 0 0)
			(layer "F.Fab")
			(hide yes)
			(effects
				(font
					(size 1.27 1.27)
					(thickness 0.15)
				)
			)
		)
		(property "Description" "SMD Multilayer Ceramic Capacitor, 0.1 µF, 50 V, 0402 [1005 Metric], ± 10%, X5R, GRM Series"
			(at 0 0 0)
			(layer "F.Fab")
			(hide yes)
			(effects
				(font
					(size 1.27 1.27)
					(thickness 0.15)
				)
			)
		)
		(property "MPN" "GRM155R61H104KE14D"
			(at 0 0 0)
			(unlocked yes)
			(layer "F.Fab")
			(hide yes)
			(effects
				(font
					(size 1 1)
					(thickness 0.15)
				)
			)
		)
		(property "Manufacturer" "Murata"
			(at 0 0 0)
			(unlocked yes)
			(layer "F.Fab")
			(hide yes)
			(effects
				(font
					(size 1 1)
					(thickness 0.15)
				)
			)
		)
		(property "License" "Apache-2.0"
			(at 0 0 0)
			(unlocked yes)
			(layer "F.Fab")
			(hide yes)
			(effects
				(font
					(size 1 1)
					(thickness 0.15)
				)
			)
		)
		(property "Author" "Antmicro"
			(at 0 0 0)
			(unlocked yes)
			(layer "F.Fab")
			(hide yes)
			(effects
				(font
					(size 1 1)
					(thickness 0.15)
				)
			)
		)
		(property "Val" "100n"
			(at 0 0 0)
			(unlocked yes)
			(layer "F.Fab")
			(hide yes)
			(effects
				(font
					(size 1 1)
					(thickness 0.15)
				)
			)
		)
		(property "Voltage" "50V"
			(at 0 0 0)
			(unlocked yes)
			(layer "F.Fab")
			(hide yes)
			(effects
				(font
					(size 1 1)
					(thickness 0.15)
				)
			)
		)
		(property "Dielectric" "X5R"
			(at 0 0 0)
			(unlocked yes)
			(layer "F.Fab")
			(hide yes)
			(effects
				(font
					(size 1 1)
					(thickness 0.15)
				)
			)
		)
		(sheetname "/X710 DCDC converters/")
		(sheetfile "DCDC_converters_X710.kicad_sch")
		(attr smd)
		(fp_rect
			(start -0.925 -0.47)
			(end 0.925 0.47)
			(stroke
				(width 0.05)
				(type default)
			)
			(fill no)
			(layer "F.CrtYd")
		)
		(fp_line
			(start -0.494 -0.25)
			(end 0.504 -0.25)
			(stroke
				(width 0.15)
				(type solid)
			)
			(layer "F.Fab")
		)
		(fp_line
			(start -0.494 0.248)
			(end -0.494 -0.25)
			(stroke
				(width 0.15)
				(type solid)
			)
			(layer "F.Fab")
		)
		(fp_line
			(start 0.504 -0.25)
			(end 0.504 0.248)
			(stroke
				(width 0.15)
				(type solid)
			)
			(layer "F.Fab")
		)
		(fp_line
			(start 0.504 0.248)
			(end -0.494 0.248)
			(stroke
				(width 0.15)
				(type solid)
			)
			(layer "F.Fab")
		)
		(fp_text user "License: Apache-2.0"
			(at -0.939 5.799 0)
			(layer "F.Fab")
			(effects
				(font
					(size 0.7 0.7)
					(thickness 0.15)
				)
				(justify left bottom)
			)
		)
		(fp_text user "${REFERENCE}"
			(at -0.939 4.599 0)
			(layer "F.Fab")
			(effects
				(font
					(size 0.7 0.7)
					(thickness 0.15)
				)
				(justify left bottom)
			)
		)
		(fp_text user "Author: Antmicro"
			(at -0.939 3.399 0)
			(layer "F.Fab")
			(effects
				(font
					(size 0.7 0.7)
					(thickness 0.15)
				)
				(justify left bottom)
			)
		)
		(pad "1" smd roundrect
			(at -0.48 0)
			(size 0.59 0.64)
			(layers "F.Cu" "F.Mask" "F.Paste")
			(roundrect_rratio 0.25)
			(net 23 "GND")
			(pintype "passive")
		)
		(pad "2" smd roundrect
			(at 0.48 0)
			(size 0.59 0.64)
			(layers "F.Cu" "F.Mask" "F.Paste")
			(roundrect_rratio 0.25)
			(net 40 "+5V")
			(pintype "passive")
		)
	)
	(footprint "antmicro-footprints:C_0603_1608Metric_EIA"
		(layer "F.Cu")
		(at 137.355 89.274999 -90)
		(descr "Capacitor SMD 0603, IPC-7351 Density Level A")
		(tags "Capacitor 0603")
		(property "Reference" "C244"
			(at 4.225001 17.105 270)
			(layer "F.SilkS")
			(effects
				(font
					(size 0.7 0.7)
					(thickness 0.15)
				)
				(justify left bottom)
			)
		)
		(property "Value" "C_22u_16V_0603"
			(at -1.42757 1.770288 270)
			(layer "F.Fab")
			(effects
				(font
					(size 0.7 0.7)
					(thickness 0.15)
				)
				(justify left bottom)
			)
		)
		(property "Datasheet" "https://product.samsungsem.com/mlcc/CL10A226MO7JZN.do"
			(at 0 0 270)
			(layer "F.Fab")
			(hide yes)
			(effects
				(font
					(size 1.27 1.27)
					(thickness 0.15)
				)
			)
		)
		(property "Description" "SMD Multilayer Ceramic Capacitor"
			(at 0 0 270)
			(layer "F.Fab")
			(hide yes)
			(effects
				(font
					(size 1.27 1.27)
					(thickness 0.15)
				)
			)
		)
		(property "MPN" "CL10A226MO7JZNC"
			(at 0 0 270)
			(unlocked yes)
			(layer "F.Fab")
			(hide yes)
			(effects
				(font
					(size 1 1)
					(thickness 0.15)
				)
			)
		)
		(property "Manufacturer" "Samsung Electro-Mechanics"
			(at 0 0 270)
			(unlocked yes)
			(layer "F.Fab")
			(hide yes)
			(effects
				(font
					(size 1 1)
					(thickness 0.15)
				)
			)
		)
		(property "License" "Apache-2.0"
			(at 0 0 270)
			(unlocked yes)
			(layer "F.Fab")
			(hide yes)
			(effects
				(font
					(size 1 1)
					(thickness 0.15)
				)
			)
		)
		(property "Author" "Antmicro"
			(at 0 0 270)
			(unlocked yes)
			(layer "F.Fab")
			(hide yes)
			(effects
				(font
					(size 1 1)
					(thickness 0.15)
				)
			)
		)
		(property "Val" "22u"
			(at 0 0 270)
			(unlocked yes)
			(layer "F.Fab")
			(hide yes)
			(effects
				(font
					(size 1 1)
					(thickness 0.15)
				)
			)
		)
		(property "Voltage" "16V"
			(at 0 0 270)
			(unlocked yes)
			(layer "F.Fab")
			(hide yes)
			(effects
				(font
					(size 1 1)
					(thickness 0.15)
				)
			)
		)
		(property "Dielectric" ""
			(at 0 0 270)
			(unlocked yes)
			(layer "F.Fab")
			(hide yes)
			(effects
				(font
					(size 1 1)
					(thickness 0.15)
				)
			)
		)
		(sheetname "/X710-AT2 power/")
		(sheetfile "x710-at2-power.kicad_sch")
		(attr smd)
		(fp_line
			(start -0.15 0.55)
			(end 0.15 0.55)
			(stroke
				(width 0.15)
				(type solid)
			)
			(layer "F.SilkS")
		)
		(fp_line
			(start -0.15 -0.55)
			(end 0.15 -0.55)
			(stroke
				(width 0.15)
				(type solid)
			)
			(layer "F.SilkS")
		)
		(fp_rect
			(start -1.25 -0.65)
			(end 1.25 0.65)
			(stroke
				(width 0.05)
				(type solid)
			)
			(fill no)
			(layer "F.CrtYd")
		)
		(fp_rect
			(start -0.8 -0.45)
			(end 0.8 0.45)
			(stroke
				(width 0.15)
				(type solid)
			)
			(fill no)
			(layer "F.Fab")
		)
		(fp_text user "Author: Antmicro"
			(at -1.682 4.894 270)
			(layer "F.Fab")
			(effects
				(font
					(size 0.7 0.7)
					(thickness 0.15)
				)
				(justify left bottom)
			)
		)
		(fp_text user "License: Apache-2.0"
			(at -1.682 5.895 270)
			(layer "F.Fab")
			(effects
				(font
					(size 0.7 0.7)
					(thickness 0.15)
				)
				(justify left bottom)
			)
		)
		(fp_text user "${REFERENCE}"
			(at -1.682 3.895 270)
			(layer "F.Fab")
			(effects
				(font
					(size 0.7 0.7)
					(thickness 0.15)
				)
				(justify left bottom)
			)
		)
		(pad "1" smd roundrect
			(at -0.7 0 270)
			(size 0.8 1.1)
			(layers "F.Cu" "F.Mask" "F.Paste")
			(roundrect_rratio 0.2)
			(net 23 "GND")
			(pintype "passive")
		)
		(pad "2" smd roundrect
			(at 0.7 0 270)
			(size 0.8 1.1)
			(layers "F.Cu" "F.Mask" "F.Paste")
			(roundrect_rratio 0.2)
			(net 7 "+3V3")
			(pintype "passive")
		)
	)
)
